#ISCELL
  mstr_misc dns *
  *
#ISCELL
  pure_quanta quanta_title_block_c *
  *
#ISCELL
  standard offpage *
  page345_i1
#CELL
  pure_quanta q_res *
  page345_i10
#ISCELL
  pure_quanta_power universal_power *
  page345_i11
#CELL
  pure_quanta q_res *
  page345_i12
#ISCELL
  standard offpage *
  page345_i13
#ISCELL
  pure_quanta_power universal_gnd *
  page345_i14
#CELL
  pure_quanta q_res *
  page345_i15
#ISCELL
  standard offpage *
  page345_i16
#ISCELL
  standard offpage *
  page345_i17
#ISCELL
  standard offpage *
  page345_i18
#CELL
  pure_quanta q_res *
  page345_i19
#ISCELL
  standard offpage *
  page345_i2
#ISCELL
  standard offpage *
  page345_i20
#CELL
  pure_quanta q_res *
  page345_i21
#ISCELL
  pure_quanta_power universal_power *
  page345_i22
#ISCELL
  standard offpage *
  page345_i23
#CELL
  pure_quanta q_res *
  page345_i24
#ISCELL
  pure_quanta_power universal_power *
  page345_i25
#ISCELL
  standard offpage *
  page345_i26
#CELL
  pure_quanta q_res *
  page345_i27
#ISCELL
  standard offpage *
  page345_i28
#ISCELL
  standard offpage *
  page345_i29
#ISCELL
  pure_quanta_power universal_gnd *
  page345_i3
#CELL
  pure_quanta q_res *
  page345_i30
#ISCELL
  standard offpage *
  page345_i31
#CELL
  pure_quanta q_res *
  page345_i32
#ISCELL
  pure_quanta_power universal_gnd *
  page345_i33
#ISCELL
  standard tap *
  page345_i34
#ISCELL
  standard tap *
  page345_i35
#ISCELL
  standard tap *
  page345_i36
#ISCELL
  standard tap *
  page345_i37
#ISCELL
  standard tap *
  page345_i38
#ISCELL
  standard tap *
  page345_i39
#ISCELL
  pure_quanta_power universal_gnd *
  page345_i4
#ISCELL
  standard offpage *
  page345_i40
#ISCELL
  standard offpage *
  page345_i41
#ISCELL
  standard offpage *
  page345_i42
#ISCELL
  standard offpage *
  page345_i43
#ISCELL
  pure_quanta_power universal_power *
  page345_i44
#ISCELL
  standard tap *
  page345_i45
#ISCELL
  standard tap *
  page345_i46
#ISCELL
  standard tap *
  page345_i47
#ISCELL
  standard tap *
  page345_i48
#ISCELL
  standard tap *
  page345_i49
#CELL
  pure_quanta sn74lvc2g07dckr *
  page345_i5
#ISCELL
  standard tap *
  page345_i50
#CELL
  pure_quanta q_res *
  page345_i51
#ISCELL
  pure_quanta_power universal_power *
  page345_i52
#CELL
  pure_quanta 74lvc1g126se7 *
  page345_i53
#ISCELL
  pure_quanta_power universal_gnd *
  page345_i54
#ISCELL
  pure_quanta_power universal_gnd *
  page345_i55
#CELL
  pure_quanta q_cap *
  page345_i56
#ISCELL
  pure_quanta_power universal_power *
  page345_i57
#CELL
  pure_quanta q_res *
  page345_i58
#ISCELL
  pure_quanta_power universal_gnd *
  page345_i59
#CELL
  pure_quanta q_cap *
  page345_i6
#CELL
  pure_quanta q_res *
  page345_i60
#ISCELL
  pure_quanta_power universal_power *
  page345_i61
#CELL
  pure_quanta q_res *
  page345_i62
#ISCELL
  standard offpage *
  page345_i63
#ISCELL
  standard offpage *
  page345_i64
#ISCELL
  standard offpage *
  page345_i65
#CELL
  pure_quanta q_res *
  page345_i66
#ISCELL
  standard offpage *
  page345_i68
#ISCELL
  standard offpage *
  page345_i69
#ISCELL
  pure_quanta_power universal_power *
  page345_i7
#ISCELL
  standard offpage *
  page345_i70
#ISCELL
  standard offpage *
  page345_i71
#ISCELL
  standard offpage *
  page345_i72
#ISCELL
  pure_quanta_power universal_power *
  page345_i73
#ISCELL
  pure_quanta_power universal_power *
  page345_i75
#ISCELL
  pure_quanta_power universal_power *
  page345_i76
#CELL
  pure_quanta q_cap *
  page345_i77
#CELL
  pure_quanta q_cap *
  page345_i78
#CELL
  pure_quanta q_cap *
  page345_i79
#CELL
  pure_quanta mosfet_nch_dual *
  page345_i8
#ISCELL
  standard offpage *
  page345_i80
#ISCELL
  pure_quanta_power universal_gnd *
  page345_i81
#ISCELL
  pure_quanta_power universal_gnd *
  page345_i82
#CELL
  pure_quanta q_res *
  page345_i83
#CELL
  pure_quanta q_cap *
  page345_i84
#CELL
  pure_quanta q_cap *
  page345_i85
#CELL
  pure_quanta q_cap *
  page345_i86
#ISCELL
  standard offpage *
  page345_i87
#CELL
  pure_quanta sconn75k_apci0155p004a *
  page345_i88
#CELL
  pure_quanta mosfet_nch_dual *
  page345_i89
#ISCELL
  pure_quanta_power universal_gnd *
  page345_i9
